(kicad_pcb
	(version 20260206)
	(generator "pcbnew")
	(generator_version "10.0")
	(general
		(thickness 1.6)
		(legacy_teardrops no)
	)
	(paper "A4")
	(title_block
		(title "riser — 13919-sa.brd")
		(comment 1 "Honey Badger (Wiwynn) / footprint 1 of 2 (GF2), pads 113-164 of 164")
	)
	(layers
		(0 "F.Cu" signal "TOP")
		(4 "In1.Cu" signal "L2VCC")
		(6 "In2.Cu" signal "L3GND")
		(2 "B.Cu" signal "BOTTOM")
		(9 "F.Adhes" user "F.Adhesive")
		(11 "B.Adhes" user "B.Adhesive")
		(13 "F.Paste" user "Package Geometry/Pastemask Top")
		(15 "B.Paste" user "Package Geometry/Pastemask Bottom")
		(5 "F.SilkS" user "Ref Des/Silkscreen Top")
		(7 "B.SilkS" user "Ref Des/Silkscreen Bottom")
		(1 "F.Mask" user "Board Geometry/Soldermask Top")
		(3 "B.Mask" user "Board Geometry/Soldermask Bottom")
		(17 "Dwgs.User" user "User.Drawings")
		(19 "Cmts.User" user "User.Comments")
		(21 "Eco1.User" user "User.Eco1")
		(23 "Eco2.User" user "User.Eco2")
		(25 "Edge.Cuts" user "Board Geometry/Outline")
		(27 "Margin" user)
		(31 "F.CrtYd" user "Package Geometry/Place Bound Top")
		(29 "B.CrtYd" user "Package Geometry/Place Bound Bottom")
		(35 "F.Fab" user "Ref Des/Assembly Top")
		(33 "B.Fab" user "Ref Des/Assembly Bottom")
	)
	(footprint ""
		(layer "F.Cu")
		(at 77.499972 -1.400048)
		(property "Reference" "GF2"
			(at 0 0 0)
			(layer "F.SilkS")
			(hide yes)
			(effects
				(font
					(size 1.27 1.27)
				)
			)
		)
		(property "Value" "GF-PCIE-164P-4-GP"
			(at -70.358 -9.0932 0)
			(unlocked yes)
			(layer "F.Fab")
			(hide yes)
			(effects
				(font
					(size 1.016 1.016)
					(thickness 0.1524)
				)
			)
		)
		(property "Device Type" "GF-PCIE-164P-4"
			(at -70.358 -10.6172 0)
			(unlocked yes)
			(layer "F.Fab")
			(hide yes)
			(effects
				(font
					(size 1.016 1.016)
					(thickness 0.1524)
				)
			)
		)
		(duplicate_pad_numbers_are_jumpers no)
		(pad "B31" smd rect
			(at -20.500086 -2.5908)
			(size 0.7112 3.2004)
			(layers "F.Cu" "F.Mask" "F.Paste")
			(net "SATA2_TX_C_DP0")
		)
		(pad "B32" smd rect
			(at -21.500084 -1.7145)
			(size 0.7112 4.191)
			(drill
				(offset 0 -0.381)
			)
			(layers "F.Cu" "F.Mask" "F.Paste")
			(net "SATA2_TX_C_DN0")
		)
		(pad "B33" smd rect
			(at -22.500082 -1.7145)
			(size 0.7112 4.191)
			(drill
				(offset 0 -0.381)
			)
			(layers "F.Cu" "F.Mask" "F.Paste")
			(net "GND")
		)
		(pad "B34" smd rect
			(at -23.50008 -1.7145)
			(size 0.7112 4.191)
			(drill
				(offset 0 -0.381)
			)
			(layers "F.Cu" "F.Mask" "F.Paste")
			(net "GND")
		)
		(pad "B35" smd rect
			(at -24.500078 -1.7145)
			(size 0.7112 4.191)
			(drill
				(offset 0 -0.381)
			)
			(layers "F.Cu" "F.Mask" "F.Paste")
			(net "CLK_100M_CLKBUFF_ENET_DP")
		)
		(pad "B36" smd rect
			(at -25.500076 -1.7145)
			(size 0.7112 4.191)
			(drill
				(offset 0 -0.381)
			)
			(layers "F.Cu" "F.Mask" "F.Paste")
			(net "CLK_100M_CLKBUFF_ENET_DN")
		)
		(pad "B37" smd rect
			(at -26.500074 -1.7145)
			(size 0.7112 4.191)
			(drill
				(offset 0 -0.381)
			)
			(layers "F.Cu" "F.Mask" "F.Paste")
			(net "GND")
		)
		(pad "B38" smd rect
			(at -27.500072 -1.7145)
			(size 0.7112 4.191)
			(drill
				(offset 0 -0.381)
			)
			(layers "F.Cu" "F.Mask" "F.Paste")
			(net "GND")
		)
		(pad "B39" smd rect
			(at -28.50007 -1.7145)
			(size 0.7112 4.191)
			(drill
				(offset 0 -0.381)
			)
			(layers "F.Cu" "F.Mask" "F.Paste")
			(net "PCIE1_RESET#")
		)
		(pad "B40" smd rect
			(at -29.500068 -1.7145)
			(size 0.7112 4.191)
			(drill
				(offset 0 -0.381)
			)
			(layers "F.Cu" "F.Mask" "F.Paste")
			(net "PCIE_RSVD_B40")
		)
		(pad "B41" smd rect
			(at -30.500066 -1.7145)
			(size 0.7112 4.191)
			(drill
				(offset 0 -0.381)
			)
			(layers "F.Cu" "F.Mask" "F.Paste")
			(net "GND")
		)
		(pad "B42" smd rect
			(at -31.500064 -1.7145)
			(size 0.7112 4.191)
			(drill
				(offset 0 -0.381)
			)
			(layers "F.Cu" "F.Mask" "F.Paste")
			(net "GND")
		)
		(pad "B43" smd rect
			(at -32.500062 -1.7145)
			(size 0.7112 4.191)
			(drill
				(offset 0 -0.381)
			)
			(layers "F.Cu" "F.Mask" "F.Paste")
			(net "GBE_SMBCLK_R")
		)
		(pad "B44" smd rect
			(at -33.50006 -1.7145)
			(size 0.7112 4.191)
			(drill
				(offset 0 -0.381)
			)
			(layers "F.Cu" "F.Mask" "F.Paste")
			(net "GBE_SMDATA_R")
		)
		(pad "B45" smd rect
			(at -34.500058 -1.7145)
			(size 0.7112 4.191)
			(drill
				(offset 0 -0.381)
			)
			(layers "F.Cu" "F.Mask" "F.Paste")
			(net "GND")
		)
		(pad "B46" smd rect
			(at -35.500056 -1.7145)
			(size 0.7112 4.191)
			(drill
				(offset 0 -0.381)
			)
			(layers "F.Cu" "F.Mask" "F.Paste")
			(net "GND")
		)
		(pad "B47" smd rect
			(at -36.500054 -1.7145)
			(size 0.7112 4.191)
			(drill
				(offset 0 -0.381)
			)
			(layers "F.Cu" "F.Mask" "F.Paste")
			(net "CPU_GBE_TX_C_DP0")
		)
		(pad "B48" smd rect
			(at -37.500052 -2.5908)
			(size 0.7112 3.2004)
			(layers "F.Cu" "F.Mask" "F.Paste")
			(net "CPU_GBE_TX_C_DN0")
		)
		(pad "B49" smd rect
			(at -38.50005 -1.7145)
			(size 0.7112 4.191)
			(drill
				(offset 0 -0.381)
			)
			(layers "F.Cu" "F.Mask" "F.Paste")
			(net "GND")
		)
		(pad "B50" smd rect
			(at -39.500048 -1.7145)
			(size 0.7112 4.191)
			(drill
				(offset 0 -0.381)
			)
			(layers "F.Cu" "F.Mask" "F.Paste")
			(net "GND")
		)
		(pad "B51" smd rect
			(at -40.500046 -1.7145)
			(size 0.7112 4.191)
			(drill
				(offset 0 -0.381)
			)
			(layers "F.Cu" "F.Mask" "F.Paste")
			(net "P2E_CPU_SAS_TX_DP4")
		)
		(pad "B52" smd rect
			(at -41.500044 -1.7145)
			(size 0.7112 4.191)
			(drill
				(offset 0 -0.381)
			)
			(layers "F.Cu" "F.Mask" "F.Paste")
			(net "P2E_CPU_SAS_TX_DN4")
		)
		(pad "B53" smd rect
			(at -42.500042 -1.7145)
			(size 0.7112 4.191)
			(drill
				(offset 0 -0.381)
			)
			(layers "F.Cu" "F.Mask" "F.Paste")
			(net "GND")
		)
		(pad "B54" smd rect
			(at -43.50004 -1.7145)
			(size 0.7112 4.191)
			(drill
				(offset 0 -0.381)
			)
			(layers "F.Cu" "F.Mask" "F.Paste")
			(net "GND")
		)
		(pad "B55" smd rect
			(at -44.500038 -1.7145)
			(size 0.7112 4.191)
			(drill
				(offset 0 -0.381)
			)
			(layers "F.Cu" "F.Mask" "F.Paste")
			(net "P2E_CPU_SAS_TX_DP5")
		)
		(pad "B56" smd rect
			(at -45.500036 -1.7145)
			(size 0.7112 4.191)
			(drill
				(offset 0 -0.381)
			)
			(layers "F.Cu" "F.Mask" "F.Paste")
			(net "P2E_CPU_SAS_TX_DN5")
		)
		(pad "B57" smd rect
			(at -46.500034 -1.7145)
			(size 0.7112 4.191)
			(drill
				(offset 0 -0.381)
			)
			(layers "F.Cu" "F.Mask" "F.Paste")
			(net "GND")
		)
		(pad "B58" smd rect
			(at -47.500032 -1.7145)
			(size 0.7112 4.191)
			(drill
				(offset 0 -0.381)
			)
			(layers "F.Cu" "F.Mask" "F.Paste")
			(net "GND")
		)
		(pad "B59" smd rect
			(at -48.50003 -1.7145)
			(size 0.7112 4.191)
			(drill
				(offset 0 -0.381)
			)
			(layers "F.Cu" "F.Mask" "F.Paste")
			(net "P2E_CPU_SAS_TX_DP6")
		)
		(pad "B60" smd rect
			(at -49.500028 -1.7145)
			(size 0.7112 4.191)
			(drill
				(offset 0 -0.381)
			)
			(layers "F.Cu" "F.Mask" "F.Paste")
			(net "P2E_CPU_SAS_TX_DN6")
		)
		(pad "B61" smd rect
			(at -50.500026 -1.7145)
			(size 0.7112 4.191)
			(drill
				(offset 0 -0.381)
			)
			(layers "F.Cu" "F.Mask" "F.Paste")
			(net "GND")
		)
		(pad "B62" smd rect
			(at -51.500024 -1.7145)
			(size 0.7112 4.191)
			(drill
				(offset 0 -0.381)
			)
			(layers "F.Cu" "F.Mask" "F.Paste")
			(net "GND")
		)
		(pad "B63" smd rect
			(at -52.500022 -1.7145)
			(size 0.7112 4.191)
			(drill
				(offset 0 -0.381)
			)
			(layers "F.Cu" "F.Mask" "F.Paste")
			(net "P2E_CPU_SAS_TX_DP7")
		)
		(pad "B64" smd rect
			(at -53.50002 -1.7145)
			(size 0.7112 4.191)
			(drill
				(offset 0 -0.381)
			)
			(layers "F.Cu" "F.Mask" "F.Paste")
			(net "P2E_CPU_SAS_TX_DN7")
		)
		(pad "B65" smd rect
			(at -54.500018 -1.7145)
			(size 0.7112 4.191)
			(drill
				(offset 0 -0.381)
			)
			(layers "F.Cu" "F.Mask" "F.Paste")
			(net "GND")
		)
		(pad "B66" smd rect
			(at -55.500016 -1.7145)
			(size 0.7112 4.191)
			(drill
				(offset 0 -0.381)
			)
			(layers "F.Cu" "F.Mask" "F.Paste")
			(net "GND")
		)
		(pad "B67" smd rect
			(at -56.500014 -1.7145)
			(size 0.7112 4.191)
			(drill
				(offset 0 -0.381)
			)
			(layers "F.Cu" "F.Mask" "F.Paste")
			(net "P2E_CPU_ETH10G_TX_DP8")
		)
		(pad "B68" smd rect
			(at -57.500012 -1.7145)
			(size 0.7112 4.191)
			(drill
				(offset 0 -0.381)
			)
			(layers "F.Cu" "F.Mask" "F.Paste")
			(net "P2E_CPU_ETH10G_TX_DN8")
		)
		(pad "B69" smd rect
			(at -58.50001 -1.7145)
			(size 0.7112 4.191)
			(drill
				(offset 0 -0.381)
			)
			(layers "F.Cu" "F.Mask" "F.Paste")
			(net "GND")
		)
		(pad "B70" smd rect
			(at -59.500008 -1.7145)
			(size 0.7112 4.191)
			(drill
				(offset 0 -0.381)
			)
			(layers "F.Cu" "F.Mask" "F.Paste")
			(net "GND")
		)
		(pad "B71" smd rect
			(at -60.500006 -1.7145)
			(size 0.7112 4.191)
			(drill
				(offset 0 -0.381)
			)
			(layers "F.Cu" "F.Mask" "F.Paste")
			(net "P2E_CPU_ETH10G_TX_DP9")
		)
		(pad "B72" smd rect
			(at -61.500004 -1.7145)
			(size 0.7112 4.191)
			(drill
				(offset 0 -0.381)
			)
			(layers "F.Cu" "F.Mask" "F.Paste")
			(net "P2E_CPU_ETH10G_TX_DN9")
		)
		(pad "B73" smd rect
			(at -62.500002 -1.7145)
			(size 0.7112 4.191)
			(drill
				(offset 0 -0.381)
			)
			(layers "F.Cu" "F.Mask" "F.Paste")
			(net "GND")
		)
		(pad "B74" smd rect
			(at -63.5 -1.7145)
			(size 0.7112 4.191)
			(drill
				(offset 0 -0.381)
			)
			(layers "F.Cu" "F.Mask" "F.Paste")
			(net "GND")
		)
		(pad "B75" smd rect
			(at -64.499998 -1.7145)
			(size 0.7112 4.191)
			(drill
				(offset 0 -0.381)
			)
			(layers "F.Cu" "F.Mask" "F.Paste")
			(net "P2E_CPU_ETH10G_TX_DP10")
		)
		(pad "B76" smd rect
			(at -65.499996 -1.7145)
			(size 0.7112 4.191)
			(drill
				(offset 0 -0.381)
			)
			(layers "F.Cu" "F.Mask" "F.Paste")
			(net "P2E_CPU_ETH10G_TX_DN10")
		)
		(pad "B77" smd rect
			(at -66.499994 -1.7145)
			(size 0.7112 4.191)
			(drill
				(offset 0 -0.381)
			)
			(layers "F.Cu" "F.Mask" "F.Paste")
			(net "GND")
		)
		(pad "B78" smd rect
			(at -67.499992 -1.7145)
			(size 0.7112 4.191)
			(drill
				(offset 0 -0.381)
			)
			(layers "F.Cu" "F.Mask" "F.Paste")
			(net "GND")
		)
		(pad "B79" smd rect
			(at -68.49999 -1.7145)
			(size 0.7112 4.191)
			(drill
				(offset 0 -0.381)
			)
			(layers "F.Cu" "F.Mask" "F.Paste")
			(net "P2E_CPU_ETH10G_TX_DP11")
		)
		(pad "B80" smd rect
			(at -69.499988 -1.7145)
			(size 0.7112 4.191)
			(drill
				(offset 0 -0.381)
			)
			(layers "F.Cu" "F.Mask" "F.Paste")
			(net "P2E_CPU_ETH10G_TX_DN11")
		)
		(pad "B81" smd rect
			(at -70.499986 -2.5908)
			(size 0.7112 3.2004)
			(layers "F.Cu" "F.Mask" "F.Paste")
			(net "GND")
		)
		(pad "B82" smd rect
			(at -71.499984 -1.7145)
			(size 0.7112 4.191)
			(drill
				(offset 0 -0.381)
			)
			(layers "F.Cu" "F.Mask" "F.Paste")
			(net "GND")
		)
	)
)
